# T6G (Grand Teton) — schematic netlist excerpt (pin names and nets, part order shuffled) for the footprints in the layout excerpt that follows; sources: Cadence DE-HDL packaged netlist, KiCad conversion of 04192023_DAF0TMB3IC0_F0TG_MB_C_brd_V02_OCP.brd

C2128  Q_CAP  22UF 4V 20% X6S  pkg C0402  page 74 : A = PVDD11_S3_P1 ; B = GND
R5028  Q_RES  4.7K 5% EMPTY  pkg 0402LF  page 28 : A = GND ; B = IRQ_BMC_SMI_N

DB15  TDR_3P  EMPTY  pkg TH2  page 260
  GND  = T1_GND
  IO1  = TDR_SE_50_OHM_IN5
  IO2  = TDR_SE_50_OHM_IN5

(kicad_pcb
	(version 20260206)
	(generator "pcbnew")
	(generator_version "10.0")
	(general
		(thickness 1.6)
		(legacy_teardrops no)
	)
	(paper "A4")
	(title_block
		(title "04192023_DAF0TMB3IC0_F0TG_MB_C_brd_V02_OCP.brd")
		(comment 1 "Grand Teton / footprints 6575-6577 of 8354")
	)
	(layers
		(0 "F.Cu" signal "TOP")
		(4 "In1.Cu" signal "GND")
		(6 "In2.Cu" signal "IN1")
		(8 "In3.Cu" signal "GND1")
		(10 "In4.Cu" signal "IN2")
		(12 "In5.Cu" signal "GND2")
		(14 "In6.Cu" signal "IN3")
		(16 "In7.Cu" signal "GND3")
		(18 "In8.Cu" signal "VCC")
		(20 "In9.Cu" signal "VCC1")
		(22 "In10.Cu" signal "GND4")
		(24 "In11.Cu" signal "IN4")
		(26 "In12.Cu" signal "GND5")
		(28 "In13.Cu" signal "IN5")
		(30 "In14.Cu" signal "GND6")
		(32 "In15.Cu" signal "IN6")
		(34 "In16.Cu" signal "GND7")
		(2 "B.Cu" signal "BOTTOM")
		(9 "F.Adhes" user "F.Adhesive")
		(11 "B.Adhes" user "B.Adhesive")
		(13 "F.Paste" user "Package Geometry/Pastemask Top")
		(15 "B.Paste" user "Package Geometry/Pastemask Bottom")
		(5 "F.SilkS" user "Ref Des/Silkscreen Top")
		(7 "B.SilkS" user "Ref Des/Silkscreen Bottom")
		(1 "F.Mask" user "Board Geometry/Soldermask Top")
		(3 "B.Mask" user "Board Geometry/Soldermask Bottom")
		(17 "Dwgs.User" user "User.Drawings")
		(19 "Cmts.User" user "User.Comments")
		(21 "Eco1.User" user "User.Eco1")
		(23 "Eco2.User" user "User.Eco2")
		(25 "Edge.Cuts" user "Board Geometry/Outline")
		(27 "Margin" user)
		(31 "F.CrtYd" user "Package Geometry/Place Bound Top")
		(29 "B.CrtYd" user "Package Geometry/Place Bound Bottom")
		(35 "F.Fab" user "Ref Des/Assembly Top")
		(33 "B.Fab" user "Ref Des/Assembly Bottom")
	)
	(footprint ""
		(layer "B.Cu")
		(at 406.717754 -330.93533)
		(property "Reference" "R5028"
			(at 0 0 0)
			(layer "B.SilkS")
			(hide yes)
			(effects
				(font
					(size 1.27 1.27)
				)
				(justify mirror)
			)
		)
		(property "Value" ""
			(at 0 0 0)
			(layer "B.Fab")
			(effects
				(font
					(size 1.27 1.27)
				)
				(justify mirror)
			)
		)
		(duplicate_pad_numbers_are_jumpers no)
		(fp_line
			(start -0.7874 -0.4064)
			(end -0.7874 0.4064)
			(stroke
				(width 0.1524)
				(type default)
			)
			(layer "B.SilkS")
		)
		(fp_line
			(start -0.7874 0.4064)
			(end 0.7874 0.4064)
			(stroke
				(width 0.1524)
				(type default)
			)
			(layer "B.SilkS")
		)
		(fp_line
			(start 0.7874 -0.4064)
			(end -0.7874 -0.4064)
			(stroke
				(width 0.1524)
				(type default)
			)
			(layer "B.SilkS")
		)
		(fp_line
			(start 0.7874 0.4064)
			(end 0.7874 -0.4064)
			(stroke
				(width 0.1524)
				(type default)
			)
			(layer "B.SilkS")
		)
		(fp_line
			(start -0.67945 -0.3048)
			(end -0.67945 0.3048)
			(stroke
				(width 0.1)
				(type default)
			)
			(layer "B.Fab")
		)
		(fp_line
			(start -0.67945 0.3048)
			(end -0.120396 0.3048)
			(stroke
				(width 0.1)
				(type default)
			)
			(layer "B.Fab")
		)
		(fp_line
			(start -0.12065 -0.3048)
			(end -0.67945 -0.3048)
			(stroke
				(width 0.1)
				(type default)
			)
			(layer "B.Fab")
		)
		(fp_line
			(start -0.12065 -0.2794)
			(end -0.12065 -0.3048)
			(stroke
				(width 0.1)
				(type default)
			)
			(layer "B.Fab")
		)
		(fp_line
			(start -0.120396 0.2794)
			(end 0.12065 0.2794)
			(stroke
				(width 0.1)
				(type default)
			)
			(layer "B.Fab")
		)
		(fp_line
			(start -0.120396 0.3048)
			(end -0.120396 0.2794)
			(stroke
				(width 0.1)
				(type default)
			)
			(layer "B.Fab")
		)
		(fp_line
			(start 0.12065 -0.305054)
			(end 0.12065 -0.2794)
			(stroke
				(width 0.1)
				(type default)
			)
			(layer "B.Fab")
		)
		(fp_line
			(start 0.12065 -0.2794)
			(end -0.12065 -0.2794)
			(stroke
				(width 0.1)
				(type default)
			)
			(layer "B.Fab")
		)
		(fp_line
			(start 0.12065 0.2794)
			(end 0.12065 0.3048)
			(stroke
				(width 0.1)
				(type default)
			)
			(layer "B.Fab")
		)
		(fp_line
			(start 0.12065 0.3048)
			(end 0.67945 0.3048)
			(stroke
				(width 0.1)
				(type default)
			)
			(layer "B.Fab")
		)
		(fp_line
			(start 0.67945 -0.305054)
			(end 0.12065 -0.305054)
			(stroke
				(width 0.1)
				(type default)
			)
			(layer "B.Fab")
		)
		(fp_line
			(start 0.67945 0.3048)
			(end 0.67945 -0.305054)
			(stroke
				(width 0.1)
				(type default)
			)
			(layer "B.Fab")
		)
		(pad "1" smd circle
			(at 0.40005 0 180)
			(size 0 0)
			(layers "B.Cu" "B.Mask" "B.Paste")
			(net "GND")
		)
		(pad "2" smd circle
			(at -0.40005 0 180)
			(size 0 0)
			(layers "B.Cu" "B.Mask" "B.Paste")
			(net "IRQ_BMC_SMI_N")
		)
	)
	(footprint ""
		(layer "B.Cu")
		(at 479.100642 -353.385882)
		(property "Reference" "DB15"
			(at 2.448814 -5.35051 270)
			(unlocked yes)
			(layer "B.SilkS")
			(effects
				(font
					(size 0.7874 0.5842)
					(thickness 0.1524)
				)
				(justify left mirror)
			)
		)
		(property "Value" ""
			(at 0 0 0)
			(layer "B.Fab")
			(effects
				(font
					(size 1.27 1.27)
				)
				(justify mirror)
			)
		)
		(duplicate_pad_numbers_are_jumpers no)
		(fp_line
			(start -3.330702 -4.771136)
			(end 0 4.011168)
			(stroke
				(width 0.1524)
				(type default)
			)
			(layer "B.SilkS")
		)
		(fp_line
			(start 0 4.011168)
			(end 3.330702 -4.771136)
			(stroke
				(width 0.1524)
				(type default)
			)
			(layer "B.SilkS")
		)
		(fp_line
			(start 3.330702 -4.771136)
			(end -3.330702 -4.771136)
			(stroke
				(width 0.1524)
				(type default)
			)
			(layer "B.SilkS")
		)
		(fp_line
			(start -3.330702 -4.771136)
			(end 0 4.011168)
			(stroke
				(width 0.1)
				(type default)
			)
			(layer "B.Fab")
		)
		(fp_line
			(start 0 4.011168)
			(end 3.330702 -4.771136)
			(stroke
				(width 0.1)
				(type default)
			)
			(layer "B.Fab")
		)
		(fp_line
			(start 3.330702 -4.771136)
			(end -3.330702 -4.771136)
			(stroke
				(width 0.1)
				(type default)
			)
			(layer "B.Fab")
		)
		(pad "1" thru_hole circle
			(at 0 0 180)
			(size 2.159 2.159)
			(drill 1.7018)
			(layers "*.Cu" "*.Mask")
			(remove_unused_layers no)
			(net "T1_GND")
			(clearance 0.0254)
			(thermal_gap 0.0254)
		)
		(pad "2" thru_hole circle
			(at 1.27 -3.348736 180)
			(size 2.159 2.159)
			(drill 1.7018)
			(layers "*.Cu" "*.Mask")
			(remove_unused_layers no)
			(net "TDR_SE_50_OHM_IN5")
			(clearance 0.0254)
			(thermal_gap 0.0254)
		)
		(pad "3" thru_hole circle
			(at -1.27 -3.348736 180)
			(size 2.159 2.159)
			(drill 1.7018)
			(layers "*.Cu" "*.Mask")
			(remove_unused_layers no)
			(net "TDR_SE_50_OHM_IN5")
			(clearance 0.0254)
			(thermal_gap 0.0254)
		)
	)
	(footprint ""
		(layer "B.Cu")
		(at 117.769386 -264.354564)
		(property "Reference" "C2128"
			(at 0 0 0)
			(layer "B.SilkS")
			(hide yes)
			(effects
				(font
					(size 1.27 1.27)
				)
				(justify mirror)
			)
		)
		(property "Value" ""
			(at 0 0 0)
			(layer "B.Fab")
			(effects
				(font
					(size 1.27 1.27)
				)
				(justify mirror)
			)
		)
		(duplicate_pad_numbers_are_jumpers no)
		(fp_line
			(start -0.7874 -0.4064)
			(end -0.7874 0.4064)
			(stroke
				(width 0.1524)
				(type default)
			)
			(layer "B.SilkS")
		)
		(fp_line
			(start -0.7874 0.4064)
			(end 0.7874 0.4064)
			(stroke
				(width 0.1524)
				(type default)
			)
			(layer "B.SilkS")
		)
		(fp_line
			(start 0.7874 -0.4064)
			(end -0.7874 -0.4064)
			(stroke
				(width 0.1524)
				(type default)
			)
			(layer "B.SilkS")
		)
		(fp_line
			(start 0.7874 0.4064)
			(end 0.7874 -0.4064)
			(stroke
				(width 0.1524)
				(type default)
			)
			(layer "B.SilkS")
		)
		(fp_line
			(start -0.67945 -0.3048)
			(end -0.67945 0.3048)
			(stroke
				(width 0.1)
				(type default)
			)
			(layer "B.Fab")
		)
		(fp_line
			(start -0.67945 0.3048)
			(end -0.120396 0.3048)
			(stroke
				(width 0.1)
				(type default)
			)
			(layer "B.Fab")
		)
		(fp_line
			(start -0.12065 -0.3048)
			(end -0.67945 -0.3048)
			(stroke
				(width 0.1)
				(type default)
			)
			(layer "B.Fab")
		)
		(fp_line
			(start -0.12065 -0.2794)
			(end -0.12065 -0.3048)
			(stroke
				(width 0.1)
				(type default)
			)
			(layer "B.Fab")
		)
		(fp_line
			(start -0.120396 0.2794)
			(end 0.12065 0.2794)
			(stroke
				(width 0.1)
				(type default)
			)
			(layer "B.Fab")
		)
		(fp_line
			(start -0.120396 0.3048)
			(end -0.120396 0.2794)
			(stroke
				(width 0.1)
				(type default)
			)
			(layer "B.Fab")
		)
		(fp_line
			(start 0.12065 -0.305054)
			(end 0.12065 -0.2794)
			(stroke
				(width 0.1)
				(type default)
			)
			(layer "B.Fab")
		)
		(fp_line
			(start 0.12065 -0.2794)
			(end -0.12065 -0.2794)
			(stroke
				(width 0.1)
				(type default)
			)
			(layer "B.Fab")
		)
		(fp_line
			(start 0.12065 0.2794)
			(end 0.12065 0.3048)
			(stroke
				(width 0.1)
				(type default)
			)
			(layer "B.Fab")
		)
		(fp_line
			(start 0.12065 0.3048)
			(end 0.67945 0.3048)
			(stroke
				(width 0.1)
				(type default)
			)
			(layer "B.Fab")
		)
		(fp_line
			(start 0.67945 -0.305054)
			(end 0.12065 -0.305054)
			(stroke
				(width 0.1)
				(type default)
			)
			(layer "B.Fab")
		)
		(fp_line
			(start 0.67945 0.3048)
			(end 0.67945 -0.305054)
			(stroke
				(width 0.1)
				(type default)
			)
			(layer "B.Fab")
		)
		(pad "1" smd circle
			(at 0.40005 0 180)
			(size 0 0)
			(layers "B.Cu" "B.Mask" "B.Paste")
			(net "PVDD11_S3_P1")
		)
		(pad "2" smd circle
			(at -0.40005 0 180)
			(size 0 0)
			(layers "B.Cu" "B.Mask" "B.Paste")
			(net "GND")
		)
	)
)
